# S9S_MB_2U (Grand Teton) — schematic netlist excerpt (pin names and nets, part order shuffled) for the footprints in the layout excerpt that follows; sources: Cadence DE-HDL packaged netlist, KiCad conversion of 03242023_DA0F0TMBIJ0_F0T_Motherboard_J_brd_V01_OCP.brd

J17  SCONN288_ADR50017P130CC  SCONN288_ADR50017-P130CC IO  pkg DDR288S_1-1VXB  page 98
  VIN_BULK0  = P12V_S3_AUX_CPU1_NVDIMM
  RFU0  = TP_CHA_CPU1_DIMM1_FRU_0
  VIN_MGMT  = P3V3_AUX
  HSCL  = I3C_SPD_DDRABCD_CPU1_LVC1_SCL_R
  HSDA  = I3C_SPD_DDRABCD_CPU1_LVC1_SDA
  VSS0  = GND
  DQ0_A  = M_A_CPU1_SA_DQ<0>
  VSS1  = GND
  DQ1_A  = M_A_CPU1_SA_DQ<1>
  VSS2  = GND
  DQS0_A_T  = M_A_CPU1_SA_DQS_DP<0>
  DQS0_A_C  = M_A_CPU1_SA_DQS_DN<0>
  VSS3  = GND
  DQ4_A  = M_A_CPU1_SA_DQ<4>
  VSS4  = GND
  DQ5_A  = M_A_CPU1_SA_DQ<5>
  VSS5  = GND
  DQ8_A  = M_A_CPU1_SA_DQ<8>
  VSS6  = GND
  DQ9_A  = M_A_CPU1_SA_DQ<9>
  VSS7  = GND
  DQS1_A_T  = M_A_CPU1_SA_DQS_DP<1>
  DQS1_A_C  = M_A_CPU1_SA_DQS_DN<1>
  VSS8  = GND
  DQ12_A  = M_A_CPU1_SA_DQ<12>
  VSS9  = GND
  DQ13_A  = M_A_CPU1_SA_DQ<13>
  VSS10  = GND
  DQ16_A  = M_A_CPU1_SA_DQ<16>
  VSS11  = GND
  DQ17_A  = M_A_CPU1_SA_DQ<17>
  VSS12  = GND
  DQS2_A_T  = M_A_CPU1_SA_DQS_DP<2>
  DQS2_A_C  = M_A_CPU1_SA_DQS_DN<2>
  VSS13  = GND
  DQ20_A  = M_A_CPU1_SA_DQ<20>
  VSS14  = GND
  DQ21_A  = M_A_CPU1_SA_DQ<21>
  VSS15  = GND
  DQ24_A  = M_A_CPU1_SA_DQ<24>
  VSS16  = GND
  DQ25_A  = M_A_CPU1_SA_DQ<25>
  VSS17  = GND
  DQS3_A_T  = M_A_CPU1_SA_DQS_DP<3>
  DQS3_A_C  = M_A_CPU1_SA_DQS_DN<3>
  VSS18  = GND
  DQ28_A  = M_A_CPU1_SA_DQ<28>
  VSS19  = GND
  DQ29_A  = M_A_CPU1_SA_DQ<29>
  VSS20  = GND
  CB0_A  = M_A_CPU1_SA_CB<0>
  VSS21  = GND
  CB1_A  = M_A_CPU1_SA_CB<1>
  VSS22  = GND
  DQS4_A_T  = M_A_CPU1_SA_DQS_DP<4>
  DQS4_A_C  = M_A_CPU1_SA_DQS_DN<4>
  VSS23  = GND
  CB4_A  = M_A_CPU1_SA_CB<4>
  VSS24  = GND
  CB5_A  = M_A_CPU1_SA_CB<5>
  VSS25  = GND
  ALERT_N  = M_A_CPU1_ALERT_N
  VSS26  = GND
  CS0_A_N  = M_A_CPU1_SA_CS_N<0>
  VSS27  = GND
  CA0_A  = M_A_CPU1_SA_CA<0>
  VSS28  = GND
  CA2_A  = M_A_CPU1_SA_CA<2>
  VSS29  = GND
  CA4_A  = M_A_CPU1_SA_CA<4>
  VSS30  = GND
  CA6_A  = M_A_CPU1_SA_CA<6>
  VSS31  = GND
  PAR_A  = M_A_CPU1_SA_PAR
  VSS32  = GND
  CA0_B  = M_A_CPU1_SB_CA<0>
  VSS33  = GND
  CA2_B  = M_A_CPU1_SB_CA<2>
  VSS34  = GND
  CA4_B  = M_A_CPU1_SB_CA<4>
  VSS35  = GND
  CA6_B  = M_A_CPU1_SB_CA<6>
  VSS36  = GND
  CS0_B_N  = M_A_CPU1_SB_CS_N<0>
  VSS37  = GND
  \lbd||rsp_a_n\  = M_A_CPU1_SA_RSP<0>
  \lbs||rsp_b_n\  = M_A_CPU1_SB_RSP<0>
  VSS38  = GND
  CB4_B  = M_A_CPU1_SB_CB<4>
  VSS39  = GND
  CB5_B  = M_A_CPU1_SB_CB<5>
  VSS40  = GND
  \dqs9_b_t||tdqs9_b_t||dbi4_b_n\  = M_A_CPU1_SB_DQS_DP<9>
  \dqs9_b_c||tdqs9_b_c\  = M_A_CPU1_SB_DQS_DN<9>
  VSS41  = GND
  CB0_B  = M_A_CPU1_SB_CB<0>
  VSS42  = GND
  CB1_B  = M_A_CPU1_SB_CB<1>
  VSS43  = GND
  DQ0_B  = M_A_CPU1_SB_DQ<0>
  VSS44  = GND
  DQ1_B  = M_A_CPU1_SB_DQ<1>
  VSS45  = GND
  DQS0_B_T  = M_A_CPU1_SB_DQS_DP<0>
  DQS0_B_C  = M_A_CPU1_SB_DQS_DN<0>
  VSS46  = GND
  DQ4_B  = M_A_CPU1_SB_DQ<4>
  VSS47  = GND
  DQ5_B  = M_A_CPU1_SB_DQ<5>
  VSS48  = GND
  DQ8_B  = M_A_CPU1_SB_DQ<8>
  VSS49  = GND
  DQ9_B  = M_A_CPU1_SB_DQ<9>
  VSS50  = GND
  DQS1_B_T  = M_A_CPU1_SB_DQS_DP<1>
  DQS1_B_C  = M_A_CPU1_SB_DQS_DN<1>
  VSS51  = GND
  DQ12_B  = M_A_CPU1_SB_DQ<12>
  VSS52  = GND
  DQ13_B  = M_A_CPU1_SB_DQ<13>
  VSS53  = GND
  DQ16_B  = M_A_CPU1_SB_DQ<16>
  VSS54  = GND
  DQ17_B  = M_A_CPU1_SB_DQ<17>
  VSS55  = GND
  DQS2_B_T  = M_A_CPU1_SB_DQS_DP<2>
  DQS2_B_C  = M_A_CPU1_SB_DQS_DN<2>
  VSS56  = GND
  DQ20_B  = M_A_CPU1_SB_DQ<20>
  VSS57  = GND
  DQ21_B  = M_A_CPU1_SB_DQ<21>
  VSS58  = GND
  DQ24_B  = M_A_CPU1_SB_DQ<24>
  VSS59  = GND
  DQ25_B  = M_A_CPU1_SB_DQ<25>
  VSS60  = GND
  DQS3_B_T  = M_A_CPU1_SB_DQS_DP<3>
  DQS3_B_C  = M_A_CPU1_SB_DQS_DN<3>
  VSS61  = GND
  DQ28_B  = M_A_CPU1_SB_DQ<28>
  VSS62  = GND
  DQ29_B  = M_A_CPU1_SB_DQ<29>
  VSS63  = GND
  RFU1  = TP_CHA_CPU1_DIMM1_FRU_1
  VIN_BULK1  = P12V_S3_AUX_CPU1_NVDIMM
  VIN_BULK2  = P12V_S3_AUX_CPU1_NVDIMM
  \pwr_good||fail_n\  = PWRGD_CHA_CPU1_DIMM1
  HSA  = PD_CHA_CPU1_DIMM1_SAA
  RFU2  = TP_CHA_CPU1_DIMM1_FRU_2
  RFU3  = TP_CHA_CPU1_DIMM1_FRU_3
  VSS64  = GND
  DQ2_A  = M_A_CPU1_SA_DQ<2>
  VSS65  = GND
  DQ3_A  = M_A_CPU1_SA_DQ<3>
  VSS66  = GND
  \dqs5_a_c||tdqs5_a_c||dqs5_a_t||tdqs5_a_t\  = M_A_CPU1_SA_DQS_DN<5>
  \dqs5_a_t||tdqs5_a_t\  = M_A_CPU1_SA_DQS_DP<5>
  VSS67  = GND
  DQ6_A  = M_A_CPU1_SA_DQ<6>
  VSS68  = GND
  DQ7_A  = M_A_CPU1_SA_DQ<7>
  VSS69  = GND
  DQ10_A  = M_A_CPU1_SA_DQ<10>
  VSS70  = GND
  DQ11_A  = M_A_CPU1_SA_DQ<11>
  VSS71  = GND
  \dqs6_a_c||tdqs6_a_c||dqs6_a_t||tdqs6_a_t\  = M_A_CPU1_SA_DQS_DN<6>
  \dqs6_a_t||tdqs6_a_t\  = M_A_CPU1_SA_DQS_DP<6>
  VSS72  = GND
  DQ14_A  = M_A_CPU1_SA_DQ<14>
  VSS73  = GND
  DQ15_A  = M_A_CPU1_SA_DQ<15>
  VSS74  = GND
  DQ18_A  = M_A_CPU1_SA_DQ<18>
  VSS75  = GND
  DQ19_A  = M_A_CPU1_SA_DQ<19>
  VSS76  = GND
  \dqs7_a_c||tdqs7_a_c\  = M_A_CPU1_SA_DQS_DN<7>
  \dqs7_a_t||tdqs7_a_t\  = M_A_CPU1_SA_DQS_DP<7>
  VSS77  = GND
  DQ22_A  = M_A_CPU1_SA_DQ<22>
  VSS78  = GND
  DQ23_A  = M_A_CPU1_SA_DQ<23>
  VSS79  = GND
  DQ26_A  = M_A_CPU1_SA_DQ<26>
  VSS80  = GND
  DQ27_A  = M_A_CPU1_SA_DQ<27>
  VSS81  = GND
  \dqs8_a_c||tdqs8_a_c\  = M_A_CPU1_SA_DQS_DN<8>
  \dqs8_a_t||tdqs8_a_t\  = M_A_CPU1_SA_DQS_DP<8>
  VSS82  = GND
  DQ30_A  = M_A_CPU1_SA_DQ<30>
  VSS83  = GND
  DQ31_A  = M_A_CPU1_SA_DQ<31>
  VSS84  = GND
  CB2_A  = M_A_CPU1_SA_CB<2>
  VSS85  = GND
  CB3_A  = M_A_CPU1_SA_CB<3>
  VSS86  = GND
  \dqs9_a_c||tdqs9_a_c\  = M_A_CPU1_SA_DQS_DN<9>
  \dqs9_a_t||tdqs9_a_t\  = M_A_CPU1_SA_DQS_DP<9>
  VSS87  = GND
  CB6_A  = M_A_CPU1_SA_CB<6>
  VSS88  = GND
  CB7_A  = M_A_CPU1_SA_CB<7>
  VSS89  = GND
  RESET_N  = RST_M_AB_CPU1_FPGA_N
  VSS90  = GND
  CS1_A_N  = M_A_CPU1_SA_CS_N<1>
  VSS91  = GND
  CA1_A  = M_A_CPU1_SA_CA<1>
  VSS92  = GND
  CA3_A  = M_A_CPU1_SA_CA<3>
  VSS93  = GND
  CA5_A  = M_A_CPU1_SA_CA<5>
  VSS94  = GND
  CK_T  = M_A_CPU1_CLK_DP<0>
  CK_C  = M_A_CPU1_CLK_DN<0>
  VSS95  = GND
  RFU4  = TP_CHA_CPU1_DIMM1_FRU_4
  CA1_B  = M_A_CPU1_SB_CA<1>
  VSS96  = GND
  CA3_B  = M_A_CPU1_SB_CA<3>
  VSS97  = GND
  CA5_B  = M_A_CPU1_SB_CA<5>
  VSS98  = GND
  PAR_B  = M_A_CPU1_SB_PAR
  VSS99  = GND
  CS1_B_N  = M_A_CPU1_SB_CS_N<1>
  VSS100  = GND
  RFU5  = TP_CHA_CPU1_DIMM1_FRU_5
  RFU6  = TP_CHA_CPU1_DIMM1_FRU_6
  VSS101  = GND
  CB6_B  = M_A_CPU1_SB_CB<6>
  VSS102  = GND
  CB7_B  = M_A_CPU1_SB_CB<7>
  VSS103  = GND
  DQS4_B_C  = M_A_CPU1_SB_DQS_DN<4>
  DQS4_B_T  = M_A_CPU1_SB_DQS_DP<4>
  VSS104  = GND
  CB2_B  = M_A_CPU1_SB_CB<2>
  VSS105  = GND
  CB3_B  = M_A_CPU1_SB_CB<3>
  VSS106  = GND
  DQ2_B  = M_A_CPU1_SB_DQ<2>
  VSS107  = GND
  DQ3_B  = M_A_CPU1_SB_DQ<3>
  VSS108  = GND
  \dqs5_b_c||tdqs5_b_c\  = M_A_CPU1_SB_DQS_DN<5>
  \dqs5_b_t||tdqs5_b_t\  = M_A_CPU1_SB_DQS_DP<5>
  VSS109  = GND
  DQ6_B  = M_A_CPU1_SB_DQ<6>
  VSS110  = GND
  DQ7_B  = M_A_CPU1_SB_DQ<7>
  VSS111  = GND
  DQ10_B  = M_A_CPU1_SB_DQ<10>
  VSS112  = GND
  DQ11_B  = M_A_CPU1_SB_DQ<11>
  VSS113  = GND
  \dqs6_b_c||tdqs6_b_c\  = M_A_CPU1_SB_DQS_DN<6>
  \dqs6_b_t||tdqs6_b_t\  = M_A_CPU1_SB_DQS_DP<6>
  VSS114  = GND
  DQ14_B  = M_A_CPU1_SB_DQ<14>
  VSS115  = GND
  DQ15_B  = M_A_CPU1_SB_DQ<15>
  VSS116  = GND
  DQ18_B  = M_A_CPU1_SB_DQ<18>
  VSS117  = GND
  DQ19_B  = M_A_CPU1_SB_DQ<19>
  VSS118  = GND
  \dqs7_b_c||tdqs7_b_c\  = M_A_CPU1_SB_DQS_DN<7>
  \dqs7_b_t||tdqs7_b_t\  = M_A_CPU1_SB_DQS_DP<7>
  VSS119  = GND
  DQ22_B  = M_A_CPU1_SB_DQ<22>
  VSS120  = GND
  DQ23_B  = M_A_CPU1_SB_DQ<23>
  VSS121  = GND
  DQ26_B  = M_A_CPU1_SB_DQ<26>
  VSS122  = GND
  DQ27_B  = M_A_CPU1_SB_DQ<27>
  VSS123  = GND
  \dqs8_b_c||tdqs8_b_c\  = M_A_CPU1_SB_DQS_DN<8>
  \dqs8_b_t||tdqs8_b_t\  = M_A_CPU1_SB_DQS_DP<8>
  VSS124  = GND
  DQ30_B  = M_A_CPU1_SB_DQ<30>
  VSS125  = GND
  DQ31_B  = M_A_CPU1_SB_DQ<31>
  VSS126  = GND
  G1  = GND
  G2  = GND
  G3  = GND

(kicad_pcb
	(version 20260206)
	(generator "pcbnew")
	(generator_version "10.0")
	(general
		(thickness 1.6)
		(legacy_teardrops no)
	)
	(paper "A4")
	(title_block
		(title "03242023_DA0F0TMBIJ0_F0T_Motherboard_J_brd_V01_OCP.brd")
		(comment 1 "Grand Teton / footprint 1335 of 6105 (J17), pads 183-228 of 291")
	)
	(layers
		(0 "F.Cu" signal "TOP")
		(4 "In1.Cu" signal "GND")
		(6 "In2.Cu" signal "IN1")
		(8 "In3.Cu" signal "GND1")
		(10 "In4.Cu" signal "IN2")
		(12 "In5.Cu" signal "GND2")
		(14 "In6.Cu" signal "IN3")
		(16 "In7.Cu" signal "GND3")
		(18 "In8.Cu" signal "VCC")
		(20 "In9.Cu" signal "VCC1")
		(22 "In10.Cu" signal "GND4")
		(24 "In11.Cu" signal "IN4")
		(26 "In12.Cu" signal "GND5")
		(28 "In13.Cu" signal "IN5")
		(30 "In14.Cu" signal "GND6")
		(32 "In15.Cu" signal "IN6")
		(34 "In16.Cu" signal "GND7")
		(2 "B.Cu" signal "BOTTOM")
		(9 "F.Adhes" user "F.Adhesive")
		(11 "B.Adhes" user "B.Adhesive")
		(13 "F.Paste" user "Package Geometry/Pastemask Top")
		(15 "B.Paste" user "Package Geometry/Pastemask Bottom")
		(5 "F.SilkS" user "Ref Des/Silkscreen Top")
		(7 "B.SilkS" user "Ref Des/Silkscreen Bottom")
		(1 "F.Mask" user "Board Geometry/Soldermask Top")
		(3 "B.Mask" user "Board Geometry/Soldermask Bottom")
		(17 "Dwgs.User" user "User.Drawings")
		(19 "Cmts.User" user "User.Comments")
		(21 "Eco1.User" user "User.Eco1")
		(23 "Eco2.User" user "User.Eco2")
		(25 "Edge.Cuts" user "Board Geometry/Outline")
		(27 "Margin" user)
		(31 "F.CrtYd" user "Package Geometry/Place Bound Top")
		(29 "B.CrtYd" user "Package Geometry/Place Bound Bottom")
		(35 "F.Fab" user "Ref Des/Assembly Top")
		(33 "B.Fab" user "Ref Des/Assembly Bottom")
	)
	(footprint ""
		(layer "F.Cu")
		(at 55.45328 -258.091686)
		(property "Reference" "J17"
			(at -0.178562 -81.717134 0)
			(unlocked yes)
			(layer "F.SilkS")
			(effects
				(font
					(size 0.7874 0.5842)
					(thickness 0.1524)
				)
				(justify left)
			)
		)
		(property "Value" ""
			(at 0 0 0)
			(layer "F.Fab")
			(effects
				(font
					(size 1.27 1.27)
				)
			)
		)
		(duplicate_pad_numbers_are_jumpers no)
		(pad "183" smd rect
			(at 2.050034 -31.025084 270)
			(size 0.519938 1.4986)
			(layers "F.Cu" "F.Mask" "F.Paste")
			(net "M_A_CPU1_SA_DQ<23>")
		)
		(pad "184" smd rect
			(at 2.050034 -30.174946 270)
			(size 0.519938 1.4986)
			(layers "F.Cu" "F.Mask" "F.Paste")
			(net "GND")
		)
		(pad "185" smd rect
			(at 2.050034 -29.325062 270)
			(size 0.519938 1.4986)
			(layers "F.Cu" "F.Mask" "F.Paste")
			(net "M_A_CPU1_SA_DQ<26>")
		)
		(pad "186" smd rect
			(at 2.050034 -28.474924 270)
			(size 0.519938 1.4986)
			(layers "F.Cu" "F.Mask" "F.Paste")
			(net "GND")
		)
		(pad "187" smd rect
			(at 2.050034 -27.62504 270)
			(size 0.519938 1.4986)
			(layers "F.Cu" "F.Mask" "F.Paste")
			(net "M_A_CPU1_SA_DQ<27>")
		)
		(pad "188" smd rect
			(at 2.050034 -26.774902 270)
			(size 0.519938 1.4986)
			(layers "F.Cu" "F.Mask" "F.Paste")
			(net "GND")
		)
		(pad "189" smd rect
			(at 2.050034 -25.925018 270)
			(size 0.519938 1.4986)
			(layers "F.Cu" "F.Mask" "F.Paste")
			(net "M_A_CPU1_SA_DQS_DN<8>")
		)
		(pad "190" smd rect
			(at 2.050034 -25.07488 270)
			(size 0.519938 1.4986)
			(layers "F.Cu" "F.Mask" "F.Paste")
			(net "M_A_CPU1_SA_DQS_DP<8>")
		)
		(pad "191" smd rect
			(at 2.050034 -24.224996 270)
			(size 0.519938 1.4986)
			(layers "F.Cu" "F.Mask" "F.Paste")
			(net "GND")
		)
		(pad "192" smd rect
			(at 2.050034 -23.375112 270)
			(size 0.519938 1.4986)
			(layers "F.Cu" "F.Mask" "F.Paste")
			(net "M_A_CPU1_SA_DQ<30>")
		)
		(pad "193" smd rect
			(at 2.050034 -22.524974 270)
			(size 0.519938 1.4986)
			(layers "F.Cu" "F.Mask" "F.Paste")
			(net "GND")
		)
		(pad "194" smd rect
			(at 2.050034 -21.67509 270)
			(size 0.519938 1.4986)
			(layers "F.Cu" "F.Mask" "F.Paste")
			(net "M_A_CPU1_SA_DQ<31>")
		)
		(pad "195" smd rect
			(at 2.050034 -20.824952 270)
			(size 0.519938 1.4986)
			(layers "F.Cu" "F.Mask" "F.Paste")
			(net "GND")
		)
		(pad "196" smd rect
			(at 2.050034 -19.975068 270)
			(size 0.519938 1.4986)
			(layers "F.Cu" "F.Mask" "F.Paste")
			(net "M_A_CPU1_SA_CB<2>")
		)
		(pad "197" smd rect
			(at 2.050034 -19.12493 270)
			(size 0.519938 1.4986)
			(layers "F.Cu" "F.Mask" "F.Paste")
			(net "GND")
		)
		(pad "198" smd rect
			(at 2.050034 -18.275046 270)
			(size 0.519938 1.4986)
			(layers "F.Cu" "F.Mask" "F.Paste")
			(net "M_A_CPU1_SA_CB<3>")
		)
		(pad "199" smd rect
			(at 2.050034 -17.424908 270)
			(size 0.519938 1.4986)
			(layers "F.Cu" "F.Mask" "F.Paste")
			(net "GND")
		)
		(pad "200" smd rect
			(at 2.050034 -16.575024 270)
			(size 0.519938 1.4986)
			(layers "F.Cu" "F.Mask" "F.Paste")
			(net "M_A_CPU1_SA_DQS_DN<9>")
		)
		(pad "201" smd rect
			(at 2.050034 -15.724886 270)
			(size 0.519938 1.4986)
			(layers "F.Cu" "F.Mask" "F.Paste")
			(net "M_A_CPU1_SA_DQS_DP<9>")
		)
		(pad "202" smd rect
			(at 2.050034 -14.875002 270)
			(size 0.519938 1.4986)
			(layers "F.Cu" "F.Mask" "F.Paste")
			(net "GND")
		)
		(pad "203" smd rect
			(at 2.050034 -14.025118 270)
			(size 0.519938 1.4986)
			(layers "F.Cu" "F.Mask" "F.Paste")
			(net "M_A_CPU1_SA_CB<6>")
		)
		(pad "204" smd rect
			(at 2.050034 -13.17498 270)
			(size 0.519938 1.4986)
			(layers "F.Cu" "F.Mask" "F.Paste")
			(net "GND")
		)
		(pad "205" smd rect
			(at 2.050034 -12.325096 270)
			(size 0.519938 1.4986)
			(layers "F.Cu" "F.Mask" "F.Paste")
			(net "M_A_CPU1_SA_CB<7>")
		)
		(pad "206" smd rect
			(at 2.050034 -11.474958 270)
			(size 0.519938 1.4986)
			(layers "F.Cu" "F.Mask" "F.Paste")
			(net "GND")
		)
		(pad "207" smd rect
			(at 2.050034 -10.625074 270)
			(size 0.519938 1.4986)
			(layers "F.Cu" "F.Mask" "F.Paste")
			(net "RST_M_AB_CPU1_FPGA_N")
		)
		(pad "208" smd rect
			(at 2.050034 -9.774936 270)
			(size 0.519938 1.4986)
			(layers "F.Cu" "F.Mask" "F.Paste")
			(net "GND")
		)
		(pad "209" smd rect
			(at 2.050034 -8.925052 270)
			(size 0.519938 1.4986)
			(layers "F.Cu" "F.Mask" "F.Paste")
			(net "M_A_CPU1_SA_CS_N<1>")
		)
		(pad "210" smd rect
			(at 2.050034 -8.074914 270)
			(size 0.519938 1.4986)
			(layers "F.Cu" "F.Mask" "F.Paste")
			(net "GND")
		)
		(pad "211" smd rect
			(at 2.050034 -7.22503 270)
			(size 0.519938 1.4986)
			(layers "F.Cu" "F.Mask" "F.Paste")
			(net "M_A_CPU1_SA_CA<1>")
		)
		(pad "212" smd rect
			(at 2.050034 -6.374892 270)
			(size 0.519938 1.4986)
			(layers "F.Cu" "F.Mask" "F.Paste")
			(net "GND")
		)
		(pad "213" smd rect
			(at 2.050034 -5.525008 270)
			(size 0.519938 1.4986)
			(layers "F.Cu" "F.Mask" "F.Paste")
			(net "M_A_CPU1_SA_CA<3>")
		)
		(pad "214" smd rect
			(at 2.050034 -4.675124 270)
			(size 0.519938 1.4986)
			(layers "F.Cu" "F.Mask" "F.Paste")
			(net "GND")
		)
		(pad "215" smd rect
			(at 2.050034 -3.824986 270)
			(size 0.519938 1.4986)
			(layers "F.Cu" "F.Mask" "F.Paste")
			(net "M_A_CPU1_SA_CA<5>")
		)
		(pad "216" smd rect
			(at 2.050034 -2.975102 270)
			(size 0.519938 1.4986)
			(layers "F.Cu" "F.Mask" "F.Paste")
			(net "GND")
		)
		(pad "217" smd rect
			(at 2.050034 -2.124964 270)
			(size 0.519938 1.4986)
			(layers "F.Cu" "F.Mask" "F.Paste")
			(net "M_A_CPU1_CLK_DP<0>")
		)
		(pad "218" smd rect
			(at 2.050034 -1.27508 270)
			(size 0.519938 1.4986)
			(layers "F.Cu" "F.Mask" "F.Paste")
			(net "M_A_CPU1_CLK_DN<0>")
		)
		(pad "219" smd rect
			(at 2.050034 -0.424942 270)
			(size 0.519938 1.4986)
			(layers "F.Cu" "F.Mask" "F.Paste")
			(net "GND")
		)
		(pad "220" smd rect
			(at 2.050034 5.525008 270)
			(size 0.519938 1.4986)
			(layers "F.Cu" "F.Mask" "F.Paste")
			(net "TP_CHA_CPU1_DIMM1_FRU_4")
		)
		(pad "221" smd rect
			(at 2.050034 6.374892 270)
			(size 0.519938 1.4986)
			(layers "F.Cu" "F.Mask" "F.Paste")
			(net "M_A_CPU1_SB_CA<1>")
		)
		(pad "222" smd rect
			(at 2.050034 7.22503 270)
			(size 0.519938 1.4986)
			(layers "F.Cu" "F.Mask" "F.Paste")
			(net "GND")
		)
		(pad "223" smd rect
			(at 2.050034 8.074914 270)
			(size 0.519938 1.4986)
			(layers "F.Cu" "F.Mask" "F.Paste")
			(net "M_A_CPU1_SB_CA<3>")
		)
		(pad "224" smd rect
			(at 2.050034 8.925052 270)
			(size 0.519938 1.4986)
			(layers "F.Cu" "F.Mask" "F.Paste")
			(net "GND")
		)
		(pad "225" smd rect
			(at 2.050034 9.774936 270)
			(size 0.519938 1.4986)
			(layers "F.Cu" "F.Mask" "F.Paste")
			(net "M_A_CPU1_SB_CA<5>")
		)
		(pad "226" smd rect
			(at 2.050034 10.625074 270)
			(size 0.519938 1.4986)
			(layers "F.Cu" "F.Mask" "F.Paste")
			(net "GND")
		)
		(pad "227" smd rect
			(at 2.050034 11.474958 270)
			(size 0.519938 1.4986)
			(layers "F.Cu" "F.Mask" "F.Paste")
			(net "M_A_CPU1_SB_PAR")
		)
		(pad "228" smd rect
			(at 2.050034 12.325096 270)
			(size 0.519938 1.4986)
			(layers "F.Cu" "F.Mask" "F.Paste")
			(net "GND")
		)
	)
)
